(kicad_pcb
	(version 20241229)
	(generator "pcbnew")
	(generator_version "9.0")
	(general
		(thickness 1.711)
		(legacy_teardrops no)
	)
	(paper "A4")
	(title_block
		(title "Antmicro Baseboard for Jetson AGX Thor")
		(date "2026-02-18")
		(rev "1.1.0")
		(company "Antmicro Ltd")
		(comment 1 "www.antmicro.com")
		(comment 9 "footprints 798-802 of 1170")
	)
	(layers
		(0 "F.Cu" signal)
		(4 "In1.Cu" signal)
		(6 "In2.Cu" signal)
		(8 "In3.Cu" signal)
		(10 "In4.Cu" jumper)
		(12 "In5.Cu" signal)
		(14 "In6.Cu" signal)
		(16 "In7.Cu" signal)
		(18 "In8.Cu" signal)
		(2 "B.Cu" signal)
		(9 "F.Adhes" user "F.Adhesive")
		(11 "B.Adhes" user "B.Adhesive")
		(13 "F.Paste" user)
		(15 "B.Paste" user)
		(5 "F.SilkS" user "F.Silkscreen")
		(7 "B.SilkS" user "B.Silkscreen")
		(1 "F.Mask" user)
		(3 "B.Mask" user)
		(17 "Dwgs.User" user "User.Drawings")
		(19 "Cmts.User" user "User.Comments")
		(21 "Eco1.User" user "User.Eco1")
		(23 "Eco2.User" user "User.Eco2")
		(25 "Edge.Cuts" user)
		(27 "Margin" user)
		(31 "F.CrtYd" user "F.Courtyard")
		(29 "B.CrtYd" user "B.Courtyard")
		(35 "F.Fab" user)
		(33 "B.Fab" user)
	)
	(footprint "antmicro-footprints:TP_SMD_0.75mm"
		(layer "B.Cu")
		(at 63 73.1 -90)
		(property "Reference" "TP109"
			(at -0.7 0.7 270)
			(layer "B.SilkS")
			(effects
				(font
					(size 0.7 0.7)
					(thickness 0.15)
				)
				(justify left bottom mirror)
			)
		)
		(property "Value" "TP_0.75mm_SMD"
			(at 0 -1.2 90)
			(layer "B.Fab")
			(effects
				(font
					(size 0.7 0.7)
					(thickness 0.15)
				)
				(justify left bottom mirror)
			)
		)
		(property "Description" "SMT test point"
			(at 0 0 90)
			(layer "B.Fab")
			(hide yes)
			(effects
				(font
					(size 1.27 1.27)
					(thickness 0.15)
				)
				(justify mirror)
			)
		)
		(property "MPN" ""
			(at 0 0 90)
			(unlocked yes)
			(layer "B.Fab")
			(hide yes)
			(effects
				(font
					(size 1 1)
					(thickness 0.15)
				)
				(justify mirror)
			)
		)
		(property "Manufacturer" ""
			(at 0 0 90)
			(unlocked yes)
			(layer "B.Fab")
			(hide yes)
			(effects
				(font
					(size 1 1)
					(thickness 0.15)
				)
				(justify mirror)
			)
		)
		(property "Author" "Antmicro"
			(at 0 0 90)
			(unlocked yes)
			(layer "B.Fab")
			(hide yes)
			(effects
				(font
					(size 1 1)
					(thickness 0.15)
				)
				(justify mirror)
			)
		)
		(property "License" "Apache-2.0"
			(at 0 0 90)
			(unlocked yes)
			(layer "B.Fab")
			(hide yes)
			(effects
				(font
					(size 1 1)
					(thickness 0.15)
				)
				(justify mirror)
			)
		)
		(sheetname "/Expansion connector/")
		(sheetfile "expansion_connector.kicad_sch")
		(attr exclude_from_pos_files exclude_from_bom)
		(fp_circle
			(center 0 0)
			(end 0.475 0)
			(stroke
				(width 0.05)
				(type default)
			)
			(fill no)
			(layer "B.CrtYd")
		)
		(fp_text user "Author: Antmicro"
			(at -0.4 -3.901 90)
			(layer "B.Fab")
			(effects
				(font
					(size 0.7 0.7)
					(thickness 0.15)
				)
				(justify left bottom mirror)
			)
		)
		(fp_text user "${REFERENCE}"
			(at -0.4 -2.7 90)
			(layer "B.Fab")
			(effects
				(font
					(size 0.7 0.7)
					(thickness 0.15)
				)
				(justify left bottom mirror)
			)
		)
		(fp_text user "License: Apache-2.0"
			(at -0.4 -5.101 90)
			(layer "B.Fab")
			(effects
				(font
					(size 0.7 0.7)
					(thickness 0.15)
				)
				(justify left bottom mirror)
			)
		)
		(pad "1" smd circle
			(at 0 0 270)
			(size 0.75 0.75)
			(layers "B.Cu" "B.Mask")
			(net 431 "Net-(J18-PadH01)")
			(pinfunction "1")
			(pintype "passive")
		)
	)
	(footprint "antmicro-footprints:R_0402_1005Metric"
		(layer "B.Cu")
		(at 109.83 134.33)
		(descr "Resistor SMD 0402")
		(tags "resistor SMD 0402")
		(property "Reference" "R216"
			(at -3.82 -0.24 0)
			(layer "B.SilkS")
			(effects
				(font
					(size 0.7 0.7)
					(thickness 0.15)
				)
				(justify right top mirror)
			)
		)
		(property "Value" "R_0R_0402"
			(at -1.011843 -1.772047 0)
			(layer "B.Fab")
			(effects
				(font
					(size 0.7 0.7)
					(thickness 0.15)
				)
				(justify right top mirror)
			)
		)
		(property "Datasheet" "https://industrial.panasonic.com/cdbs/www-data/pdf/RDA0000/AOA0000C301.pdf"
			(at 0 0 0)
			(layer "B.Fab")
			(hide yes)
			(effects
				(font
					(size 1.27 1.27)
					(thickness 0.15)
				)
				(justify mirror)
			)
		)
		(property "Description" "SMD Chip Resistor, Jumper, 0 ohm, 100 mW, 0402 [1005 Metric], Thick Film, General Purpose"
			(at 0 0 0)
			(layer "B.Fab")
			(hide yes)
			(effects
				(font
					(size 1.27 1.27)
					(thickness 0.15)
				)
				(justify mirror)
			)
		)
		(property "MPN" "ERJ2GE0R00X"
			(at 0 0 180)
			(unlocked yes)
			(layer "B.Fab")
			(hide yes)
			(effects
				(font
					(size 1 1)
					(thickness 0.15)
				)
				(justify mirror)
			)
		)
		(property "Manufacturer" "Panasonic"
			(at 0 0 180)
			(unlocked yes)
			(layer "B.Fab")
			(hide yes)
			(effects
				(font
					(size 1 1)
					(thickness 0.15)
				)
				(justify mirror)
			)
		)
		(property "License" "Apache-2.0"
			(at 0 0 180)
			(unlocked yes)
			(layer "B.Fab")
			(hide yes)
			(effects
				(font
					(size 1 1)
					(thickness 0.15)
				)
				(justify mirror)
			)
		)
		(property "Author" "Antmicro"
			(at 0 0 180)
			(unlocked yes)
			(layer "B.Fab")
			(hide yes)
			(effects
				(font
					(size 1 1)
					(thickness 0.15)
				)
				(justify mirror)
			)
		)
		(property "Val" "0R"
			(at 0 0 180)
			(unlocked yes)
			(layer "B.Fab")
			(hide yes)
			(effects
				(font
					(size 1 1)
					(thickness 0.15)
				)
				(justify mirror)
			)
		)
		(property "Tolerance" "~"
			(at 0 0 180)
			(unlocked yes)
			(layer "B.Fab")
			(hide yes)
			(effects
				(font
					(size 1 1)
					(thickness 0.15)
				)
				(justify mirror)
			)
		)
		(property "Current" "1A"
			(at 0 0 180)
			(unlocked yes)
			(layer "B.Fab")
			(hide yes)
			(effects
				(font
					(size 1 1)
					(thickness 0.15)
				)
				(justify mirror)
			)
		)
		(sheetname "/M.2/")
		(sheetfile "m2.kicad_sch")
		(attr smd)
		(fp_rect
			(start -0.925 0.47)
			(end 0.925 -0.47)
			(stroke
				(width 0.05)
				(type default)
			)
			(fill no)
			(layer "B.CrtYd")
		)
		(fp_rect
			(start -0.5 0.25)
			(end 0.5 -0.25)
			(stroke
				(width 0.15)
				(type solid)
			)
			(fill no)
			(layer "B.Fab")
		)
		(fp_text user "${REFERENCE}"
			(at -0.95 -3.168 0)
			(layer "B.Fab")
			(effects
				(font
					(size 0.7 0.7)
					(thickness 0.15)
				)
				(justify right top mirror)
			)
		)
		(fp_text user "Author: Antmicro"
			(at -0.95 -4.169 0)
			(layer "B.Fab")
			(effects
				(font
					(size 0.7 0.7)
					(thickness 0.15)
				)
				(justify right top mirror)
			)
		)
		(fp_text user "License: Apache-2.0"
			(at -0.95 -5.169 0)
			(layer "B.Fab")
			(effects
				(font
					(size 0.7 0.7)
					(thickness 0.15)
				)
				(justify right top mirror)
			)
		)
		(pad "1" smd roundrect
			(at -0.48 0)
			(size 0.59 0.64)
			(layers "B.Cu" "B.Mask" "B.Paste")
			(roundrect_rratio 0.25)
			(net 104 "/M.2/~{PEWAKE}")
			(pintype "passive")
		)
		(pad "2" smd roundrect
			(at 0.48 0)
			(size 0.59 0.64)
			(layers "B.Cu" "B.Mask" "B.Paste")
			(roundrect_rratio 0.25)
			(net 833 "/M.2/~{PEWAKE_E}")
			(pintype "passive")
		)
	)
	(footprint "antmicro-footprints:C_0603_1608Metric_EIA"
		(layer "B.Cu")
		(at 124.6 97)
		(descr "Capacitor SMD 0603, IPC-7351 Density Level A")
		(tags "Capacitor 0603")
		(property "Reference" "C193"
			(at 1.2 -0.4 0)
			(layer "B.SilkS")
			(effects
				(font
					(size 0.7 0.7)
					(thickness 0.15)
				)
				(justify right top mirror)
			)
		)
		(property "Value" "C_22u_16V_0603"
			(at -1.42757 -1.770288 0)
			(layer "B.Fab")
			(effects
				(font
					(size 0.7 0.7)
					(thickness 0.15)
				)
				(justify right top mirror)
			)
		)
		(property "Datasheet" "https://product.samsungsem.com/mlcc/CL10A226MO7JZN.do"
			(at 0 0 0)
			(layer "B.Fab")
			(hide yes)
			(effects
				(font
					(size 1.27 1.27)
					(thickness 0.15)
				)
				(justify mirror)
			)
		)
		(property "Description" "SMD Multilayer Ceramic Capacitor"
			(at 0 0 0)
			(layer "B.Fab")
			(hide yes)
			(effects
				(font
					(size 1.27 1.27)
					(thickness 0.15)
				)
				(justify mirror)
			)
		)
		(property "Manufacturer" "Samsung Electro-Mechanics"
			(at 0 0 180)
			(unlocked yes)
			(layer "B.Fab")
			(hide yes)
			(effects
				(font
					(size 1 1)
					(thickness 0.15)
				)
				(justify mirror)
			)
		)
		(property "MPN" "CL10A226MO7JZNC"
			(at 0 0 180)
			(unlocked yes)
			(layer "B.Fab")
			(hide yes)
			(effects
				(font
					(size 1 1)
					(thickness 0.15)
				)
				(justify mirror)
			)
		)
		(property "Val" "22u"
			(at 0 0 180)
			(unlocked yes)
			(layer "B.Fab")
			(hide yes)
			(effects
				(font
					(size 1 1)
					(thickness 0.15)
				)
				(justify mirror)
			)
		)
		(property "License" "Apache-2.0"
			(at 0 0 180)
			(unlocked yes)
			(layer "B.Fab")
			(hide yes)
			(effects
				(font
					(size 1 1)
					(thickness 0.15)
				)
				(justify mirror)
			)
		)
		(property "Author" "Antmicro"
			(at 0 0 180)
			(unlocked yes)
			(layer "B.Fab")
			(hide yes)
			(effects
				(font
					(size 1 1)
					(thickness 0.15)
				)
				(justify mirror)
			)
		)
		(property "Voltage" "16V"
			(at 0 0 180)
			(unlocked yes)
			(layer "B.Fab")
			(hide yes)
			(effects
				(font
					(size 1 1)
					(thickness 0.15)
				)
				(justify mirror)
			)
		)
		(property "Dielectric" "template_dielectric"
			(at 0 0 180)
			(unlocked yes)
			(layer "B.Fab")
			(hide yes)
			(effects
				(font
					(size 1 1)
					(thickness 0.15)
				)
				(justify mirror)
			)
		)
		(sheetname "/M.2/")
		(sheetfile "m2.kicad_sch")
		(attr smd)
		(fp_line
			(start -0.15 -0.55)
			(end 0.15 -0.55)
			(stroke
				(width 0.15)
				(type solid)
			)
			(layer "B.SilkS")
		)
		(fp_line
			(start -0.15 0.55)
			(end 0.15 0.55)
			(stroke
				(width 0.15)
				(type solid)
			)
			(layer "B.SilkS")
		)
		(fp_poly
			(pts
				(xy -1.25 0.65) (xy -1.25 -0.65) (xy 1.25 -0.65) (xy 1.25 0.65)
			)
			(stroke
				(width 0.05)
				(type solid)
			)
			(fill no)
			(layer "B.CrtYd")
		)
		(fp_poly
			(pts
				(xy -0.799999 0.45) (xy -0.799999 -0.45) (xy 0.799999 -0.45) (xy 0.799999 0.45)
			)
			(stroke
				(width 0.15)
				(type solid)
			)
			(fill no)
			(layer "B.Fab")
		)
		(fp_text user "${REFERENCE}"
			(at -1.682001 -3.895 0)
			(layer "B.Fab")
			(effects
				(font
					(size 0.7 0.7)
					(thickness 0.15)
				)
				(justify right top mirror)
			)
		)
		(fp_text user "Author: Antmicro"
			(at -1.682 -4.894 0)
			(layer "B.Fab")
			(effects
				(font
					(size 0.7 0.7)
					(thickness 0.15)
				)
				(justify right top mirror)
			)
		)
		(fp_text user "License: Apache-2.0"
			(at -1.682 -5.895 0)
			(layer "B.Fab")
			(effects
				(font
					(size 0.7 0.7)
					(thickness 0.15)
				)
				(justify right top mirror)
			)
		)
		(pad "1" smd roundrect
			(at -0.7 0)
			(size 0.8 1.1)
			(layers "B.Cu" "B.Mask" "B.Paste")
			(roundrect_rratio 0.2)
			(net 14 "/M.2/3V3_M2")
			(pintype "passive")
		)
		(pad "2" smd roundrect
			(at 0.7 0)
			(size 0.8 1.1)
			(layers "B.Cu" "B.Mask" "B.Paste")
			(roundrect_rratio 0.2)
			(net 1 "GND")
			(pintype "passive")
		)
	)
	(footprint "antmicro-footprints:C_0402_1005Metric"
		(layer "B.Cu")
		(at 142.6 65.2 -90)
		(descr "Capacitor SMD 0402")
		(tags "capacitor SMD 0402")
		(property "Reference" "C210"
			(at 0.9 -0.4 90)
			(layer "B.SilkS")
			(effects
				(font
					(size 0.7 0.7)
					(thickness 0.15)
				)
				(justify left bottom mirror)
			)
		)
		(property "Value" "C_100n_0402"
			(at -1.022927 -2.155213 90)
			(layer "B.Fab")
			(effects
				(font
					(size 0.7 0.7)
					(thickness 0.15)
				)
				(justify left bottom mirror)
			)
		)
		(property "Datasheet" "https://www.murata.com/products/productdetail?partno=GRM155R61H104KE14%23"
			(at 0 0 90)
			(layer "B.Fab")
			(hide yes)
			(effects
				(font
					(size 1.27 1.27)
					(thickness 0.15)
				)
				(justify mirror)
			)
		)
		(property "Description" "SMD Multilayer Ceramic Capacitor, 0.1 µF, 50 V, 0402 [1005 Metric], ± 10%, X5R, GRM Series"
			(at 0 0 90)
			(layer "B.Fab")
			(hide yes)
			(effects
				(font
					(size 1.27 1.27)
					(thickness 0.15)
				)
				(justify mirror)
			)
		)
		(property "Manufacturer" "Murata"
			(at 0 0 90)
			(unlocked yes)
			(layer "B.Fab")
			(hide yes)
			(effects
				(font
					(size 1 1)
					(thickness 0.15)
				)
				(justify mirror)
			)
		)
		(property "MPN" "GRM155R61H104KE14D"
			(at 0 0 90)
			(unlocked yes)
			(layer "B.Fab")
			(hide yes)
			(effects
				(font
					(size 1 1)
					(thickness 0.15)
				)
				(justify mirror)
			)
		)
		(property "Val" "100n"
			(at 0 0 90)
			(unlocked yes)
			(layer "B.Fab")
			(hide yes)
			(effects
				(font
					(size 1 1)
					(thickness 0.15)
				)
				(justify mirror)
			)
		)
		(property "License" "Apache-2.0"
			(at 0 0 90)
			(unlocked yes)
			(layer "B.Fab")
			(hide yes)
			(effects
				(font
					(size 1 1)
					(thickness 0.15)
				)
				(justify mirror)
			)
		)
		(property "Author" "Antmicro"
			(at 0 0 90)
			(unlocked yes)
			(layer "B.Fab")
			(hide yes)
			(effects
				(font
					(size 1 1)
					(thickness 0.15)
				)
				(justify mirror)
			)
		)
		(property "Voltage" "50V"
			(at 0 0 90)
			(unlocked yes)
			(layer "B.Fab")
			(hide yes)
			(effects
				(font
					(size 1 1)
					(thickness 0.15)
				)
				(justify mirror)
			)
		)
		(property "Dielectric" "X5R"
			(at 0 0 90)
			(unlocked yes)
			(layer "B.Fab")
			(hide yes)
			(effects
				(font
					(size 1 1)
					(thickness 0.15)
				)
				(justify mirror)
			)
		)
		(sheetname "/Peripherals/")
		(sheetfile "peripherals.kicad_sch")
		(attr smd)
		(fp_poly
			(pts
				(xy -0.925 0.47) (xy 0.925 0.47) (xy 0.925 -0.47) (xy -0.925 -0.47)
			)
			(stroke
				(width 0.05)
				(type default)
			)
			(fill no)
			(layer "B.CrtYd")
		)
		(fp_line
			(start -0.494 0.25)
			(end 0.504 0.25)
			(stroke
				(width 0.15)
				(type solid)
			)
			(layer "B.Fab")
		)
		(fp_line
			(start 0.504 0.25)
			(end 0.504 -0.248)
			(stroke
				(width 0.15)
				(type solid)
			)
			(layer "B.Fab")
		)
		(fp_line
			(start -0.494 -0.248)
			(end -0.494 0.25)
			(stroke
				(width 0.15)
				(type solid)
			)
			(layer "B.Fab")
		)
		(fp_line
			(start 0.504 -0.248)
			(end -0.494 -0.248)
			(stroke
				(width 0.15)
				(type solid)
			)
			(layer "B.Fab")
		)
		(fp_text user "${REFERENCE}"
			(at -0.939 -4.599 90)
			(layer "B.Fab")
			(effects
				(font
					(size 0.7 0.7)
					(thickness 0.15)
				)
				(justify left bottom mirror)
			)
		)
		(fp_text user "License: Apache-2.0"
			(at -0.939 -5.799 90)
			(layer "B.Fab")
			(effects
				(font
					(size 0.7 0.7)
					(thickness 0.15)
				)
				(justify left bottom mirror)
			)
		)
		(fp_text user "Author: Antmicro"
			(at -0.939 -3.399 90)
			(layer "B.Fab")
			(effects
				(font
					(size 0.7 0.7)
					(thickness 0.15)
				)
				(justify left bottom mirror)
			)
		)
		(pad "1" smd roundrect
			(at -0.48 0 270)
			(size 0.59 0.64)
			(layers "B.Cu" "B.Mask" "B.Paste")
			(roundrect_rratio 0.25)
			(net 2 "+3V3")
			(pintype "passive")
		)
		(pad "2" smd roundrect
			(at 0.48 0 270)
			(size 0.59 0.64)
			(layers "B.Cu" "B.Mask" "B.Paste")
			(roundrect_rratio 0.25)
			(net 1 "GND")
			(pintype "passive")
		)
	)
	(footprint "antmicro-footprints:TP_SMD_0.75mm"
		(layer "B.Cu")
		(at 202.8 116.4 180)
		(property "Reference" "TP67"
			(at 0.4 0.6 90)
			(layer "B.SilkS")
			(effects
				(font
					(size 0.7 0.7)
					(thickness 0.15)
				)
				(justify right top mirror)
			)
		)
		(property "Value" "TP_0.75mm_SMD"
			(at 0 -1.2 180)
			(layer "B.Fab")
			(effects
				(font
					(size 0.7 0.7)
					(thickness 0.15)
				)
				(justify right top mirror)
			)
		)
		(property "Description" "SMT test point"
			(at 0 0 180)
			(layer "B.Fab")
			(hide yes)
			(effects
				(font
					(size 1.27 1.27)
					(thickness 0.15)
				)
				(justify mirror)
			)
		)
		(property "MPN" ""
			(at 0 0 0)
			(unlocked yes)
			(layer "B.Fab")
			(hide yes)
			(effects
				(font
					(size 1 1)
					(thickness 0.15)
				)
				(justify mirror)
			)
		)
		(property "Manufacturer" ""
			(at 0 0 0)
			(unlocked yes)
			(layer "B.Fab")
			(hide yes)
			(effects
				(font
					(size 1 1)
					(thickness 0.15)
				)
				(justify mirror)
			)
		)
		(property "Author" "Antmicro"
			(at 0 0 0)
			(unlocked yes)
			(layer "B.Fab")
			(hide yes)
			(effects
				(font
					(size 1 1)
					(thickness 0.15)
				)
				(justify mirror)
			)
		)
		(property "License" "Apache-2.0"
			(at 0 0 0)
			(unlocked yes)
			(layer "B.Fab")
			(hide yes)
			(effects
				(font
					(size 1 1)
					(thickness 0.15)
				)
				(justify mirror)
			)
		)
		(sheetname "/USB Hub/")
		(sheetfile "usb_hub.kicad_sch")
		(attr exclude_from_pos_files exclude_from_bom)
		(fp_circle
			(center 0 0)
			(end 0.475 0)
			(stroke
				(width 0.05)
				(type default)
			)
			(fill no)
			(layer "B.CrtYd")
		)
		(fp_text user "Author: Antmicro"
			(at -0.4 -3.901 180)
			(layer "B.Fab")
			(effects
				(font
					(size 0.7 0.7)
					(thickness 0.15)
				)
				(justify right top mirror)
			)
		)
		(fp_text user "${REFERENCE}"
			(at -0.4 -2.7 180)
			(layer "B.Fab")
			(effects
				(font
					(size 0.7 0.7)
					(thickness 0.15)
				)
				(justify right top mirror)
			)
		)
		(fp_text user "License: Apache-2.0"
			(at -0.4 -5.101 180)
			(layer "B.Fab")
			(effects
				(font
					(size 0.7 0.7)
					(thickness 0.15)
				)
				(justify right top mirror)
			)
		)
		(pad "1" smd circle
			(at 0 0 180)
			(size 0.75 0.75)
			(layers "B.Cu" "B.Mask")
			(net 1084 "/USB Hub/DP1_VCONN1")
			(pinfunction "1")
			(pintype "passive")
		)
	)
)
